# BASEBOARD_FAB2 (Tioga Pass) — schematic netlist excerpt (pin names and nets, part order shuffled) for the footprints in the layout excerpt that follows; sources: Cadence DE-HDL packaged netlist, KiCad conversion of Wiwynn_Tioga_Pass_MB.brd

C8U6  CAP_A  47UF 4V 20% X5R  pkg 0603V  page 225 : A = PVDDQ_GHJ ; B = GND
R3R16  RES  4.75K 1% CHIP  pkg 0402  page 192 : A = PVPP_ABC ; B = RST_CD_CPU0_POR_N
C5P40  CAP  47UF 4V 20% X6S  pkg 0805  page 42 : A = PVCCIN_CPU0 ; B = GND

(kicad_pcb
	(version 20260206)
	(generator "pcbnew")
	(generator_version "10.0")
	(general
		(thickness 1.6)
		(legacy_teardrops no)
	)
	(paper "A4")
	(title_block
		(title "Wiwynn_Tioga_Pass_MB.brd")
		(comment 1 "Tioga Pass / footprints 2567-2569 of 4770")
	)
	(layers
		(0 "F.Cu" signal "TOP")
		(4 "In1.Cu" signal "L2GND")
		(6 "In2.Cu" signal "L3")
		(8 "In3.Cu" signal "L4GND")
		(10 "In4.Cu" signal "L5")
		(12 "In5.Cu" signal "L6GND")
		(14 "In6.Cu" signal "L7VCC")
		(16 "In7.Cu" signal "L8VCC")
		(18 "In8.Cu" signal "L9GND")
		(20 "In9.Cu" signal "L10")
		(22 "In10.Cu" signal "L11GND")
		(24 "In11.Cu" signal "L12")
		(26 "In12.Cu" signal "L13GND")
		(2 "B.Cu" signal "BOTTOM")
		(9 "F.Adhes" user "F.Adhesive")
		(11 "B.Adhes" user "B.Adhesive")
		(13 "F.Paste" user "Package Geometry/Pastemask Top")
		(15 "B.Paste" user "Package Geometry/Pastemask Bottom")
		(5 "F.SilkS" user "Ref Des/Silkscreen Top")
		(7 "B.SilkS" user "Ref Des/Silkscreen Bottom")
		(1 "F.Mask" user "Board Geometry/Soldermask Top")
		(3 "B.Mask" user "Board Geometry/Soldermask Bottom")
		(17 "Dwgs.User" user "User.Drawings")
		(19 "Cmts.User" user "User.Comments")
		(21 "Eco1.User" user "User.Eco1")
		(23 "Eco2.User" user "User.Eco2")
		(25 "Edge.Cuts" user "Board Geometry/Outline")
		(27 "Margin" user)
		(31 "F.CrtYd" user "Package Geometry/Place Bound Top")
		(29 "B.CrtYd" user "Package Geometry/Place Bound Bottom")
		(35 "F.Fab" user "Ref Des/Assembly Top")
		(33 "B.Fab" user "Ref Des/Assembly Bottom")
	)
	(footprint ""
		(layer "B.Cu")
		(at 323.758306 -29.812742 -90)
		(property "Reference" "R3R16"
			(at 0 0 90)
			(layer "B.SilkS")
			(hide yes)
			(effects
				(font
					(size 1.27 1.27)
				)
				(justify mirror)
			)
		)
		(property "Value" ""
			(at 0 0 90)
			(layer "B.Fab")
			(effects
				(font
					(size 1.27 1.27)
				)
				(justify mirror)
			)
		)
		(duplicate_pad_numbers_are_jumpers no)
		(fp_poly
			(pts
				(xy 0.2794 -0.1016) (xy -0.2794 -0.1016) (xy -0.2794 0.9906) (xy 0.2794 0.9906)
			)
			(stroke
				(width 0)
				(type default)
			)
			(fill no)
			(layer "B.CrtYd")
		)
		(fp_line
			(start -0.2794 0.9906)
			(end -0.2794 -0.1016)
			(stroke
				(width 0.1)
				(type default)
			)
			(layer "B.Fab")
		)
		(fp_line
			(start 0.2794 0.9906)
			(end -0.2794 0.9906)
			(stroke
				(width 0.1)
				(type default)
			)
			(layer "B.Fab")
		)
		(fp_line
			(start -0.2794 -0.1016)
			(end 0.2794 -0.1016)
			(stroke
				(width 0.1)
				(type default)
			)
			(layer "B.Fab")
		)
		(fp_line
			(start 0.2794 -0.1016)
			(end 0.2794 0.9906)
			(stroke
				(width 0.1)
				(type default)
			)
			(layer "B.Fab")
		)
		(pad "1" smd rect
			(at 0 0 90)
			(size 0.508 0.508)
			(layers "B.Cu" "B.Mask" "B.Paste")
			(net "PVPP_ABC")
		)
		(pad "2" smd rect
			(at 0 0.889 90)
			(size 0.508 0.508)
			(layers "B.Cu" "B.Mask" "B.Paste")
			(net "RST_CD_CPU0_POR_N")
		)
		(zone
			(layer "B.Cu")
			(hatch none 0.5)
			(connect_pads
				(clearance 0)
			)
			(min_thickness 0.25)
			(keepout
				(tracks not_allowed)
				(vias allowed)
				(pads allowed)
				(copperpour not_allowed)
				(footprints allowed)
			)
			(placement
				(enabled no)
				(sheetname "")
			)
			(fill
				(thermal_gap 0.5)
				(thermal_bridge_width 0.5)
				(island_removal_mode 0)
			)
			(polygon
				(pts
					(xy 323.123306 -29.558742) (xy 323.123306 -30.066742) (xy 323.504306 -30.066742) (xy 323.504306 -29.558742)
				)
			)
		)
		(zone
			(layer "B.Cu")
			(hatch none 0.5)
			(connect_pads
				(clearance 0)
			)
			(min_thickness 0.25)
			(keepout
				(tracks allowed)
				(vias not_allowed)
				(pads allowed)
				(copperpour not_allowed)
				(footprints allowed)
			)
			(placement
				(enabled no)
				(sheetname "")
			)
			(fill
				(thermal_gap 0.5)
				(thermal_bridge_width 0.5)
				(island_removal_mode 0)
			)
			(polygon
				(pts
					(xy 323.504306 -29.558742) (xy 323.504306 -30.066742) (xy 323.123306 -30.066742) (xy 323.123306 -29.558742)
				)
			)
		)
	)
	(footprint ""
		(layer "B.Cu")
		(at 83.856068 -8.1534 -90)
		(property "Reference" "C8U6"
			(at -1.848866 0.752348 270)
			(unlocked yes)
			(layer "B.SilkS")
			(effects
				(font
					(size 1.27 0.9652)
					(thickness 0.1524)
				)
				(justify mirror)
			)
		)
		(property "Value" ""
			(at 0 0 90)
			(layer "B.Fab")
			(effects
				(font
					(size 1.27 1.27)
				)
				(justify mirror)
			)
		)
		(duplicate_pad_numbers_are_jumpers no)
		(fp_rect
			(start 0.500126 1.598422)
			(end -0.500126 -0.201422)
			(stroke
				(width 0)
				(type default)
			)
			(fill no)
			(layer "B.CrtYd")
		)
		(fp_line
			(start -0.500126 1.598422)
			(end 0.500126 1.598422)
			(stroke
				(width 0.1)
				(type default)
			)
			(layer "B.Fab")
		)
		(fp_line
			(start 0.500126 1.598422)
			(end 0.500126 -0.201422)
			(stroke
				(width 0.1)
				(type default)
			)
			(layer "B.Fab")
		)
		(fp_line
			(start -0.500126 -0.201422)
			(end -0.500126 1.598422)
			(stroke
				(width 0.1)
				(type default)
			)
			(layer "B.Fab")
		)
		(fp_line
			(start 0.500126 -0.201422)
			(end -0.500126 -0.201422)
			(stroke
				(width 0.1)
				(type default)
			)
			(layer "B.Fab")
		)
		(pad "1" smd rect
			(at 0 0 180)
			(size 0.889 0.9906)
			(layers "B.Cu" "B.Mask" "B.Paste")
			(net "PVDDQ_GHJ")
		)
		(pad "2" smd rect
			(at 0 1.397 180)
			(size 0.889 0.9906)
			(layers "B.Cu" "B.Mask" "B.Paste")
			(net "GND")
		)
		(zone
			(layer "B.Cu")
			(hatch none 0.5)
			(connect_pads
				(clearance 0)
			)
			(min_thickness 0.25)
			(keepout
				(tracks not_allowed)
				(vias allowed)
				(pads allowed)
				(copperpour not_allowed)
				(footprints allowed)
			)
			(placement
				(enabled no)
				(sheetname "")
			)
			(fill
				(thermal_gap 0.5)
				(thermal_bridge_width 0.5)
				(island_removal_mode 0)
			)
			(polygon
				(pts
					(xy 82.903568 -7.6581) (xy 83.411568 -7.6581) (xy 83.411568 -8.6487) (xy 82.903568 -8.6487)
				)
			)
		)
		(zone
			(layer "B.Cu")
			(hatch none 0.5)
			(connect_pads
				(clearance 0)
			)
			(min_thickness 0.25)
			(keepout
				(tracks allowed)
				(vias not_allowed)
				(pads allowed)
				(copperpour not_allowed)
				(footprints allowed)
			)
			(placement
				(enabled no)
				(sheetname "")
			)
			(fill
				(thermal_gap 0.5)
				(thermal_bridge_width 0.5)
				(island_removal_mode 0)
			)
			(polygon
				(pts
					(xy 82.903568 -7.6581) (xy 83.411568 -7.6581) (xy 83.411568 -8.6487) (xy 82.903568 -8.6487)
				)
			)
		)
	)
	(footprint ""
		(layer "B.Cu")
		(at 275.262086 -68.17614 180)
		(property "Reference" "C5P40"
			(at 0 0 0)
			(layer "B.SilkS")
			(hide yes)
			(effects
				(font
					(size 1.27 1.27)
				)
				(justify mirror)
			)
		)
		(property "Value" ""
			(at 0 0 0)
			(layer "B.Fab")
			(effects
				(font
					(size 1.27 1.27)
				)
				(justify mirror)
			)
		)
		(duplicate_pad_numbers_are_jumpers no)
		(fp_poly
			(pts
				(xy 0.7239 -0.2159) (xy -0.7239 -0.2159) (xy -0.7239 1.9939) (xy 0.7239 1.9939)
			)
			(stroke
				(width 0)
				(type default)
			)
			(fill no)
			(layer "B.CrtYd")
		)
		(fp_line
			(start 0.7239 1.9939)
			(end -0.7239 1.9939)
			(stroke
				(width 0.1)
				(type default)
			)
			(layer "B.Fab")
		)
		(fp_line
			(start 0.7239 -0.2159)
			(end 0.7239 1.9939)
			(stroke
				(width 0.1)
				(type default)
			)
			(layer "B.Fab")
		)
		(fp_line
			(start -0.7239 1.9939)
			(end -0.7239 -0.2159)
			(stroke
				(width 0.1)
				(type default)
			)
			(layer "B.Fab")
		)
		(fp_line
			(start -0.7239 -0.2159)
			(end 0.7239 -0.2159)
			(stroke
				(width 0.1)
				(type default)
			)
			(layer "B.Fab")
		)
		(pad "1" smd rect
			(at 0 0)
			(size 1.27 1.016)
			(layers "B.Cu" "B.Mask" "B.Paste")
			(net "PVCCIN_CPU0")
		)
		(pad "2" smd rect
			(at 0 1.778)
			(size 1.27 1.016)
			(layers "B.Cu" "B.Mask" "B.Paste")
			(net "GND")
		)
		(zone
			(layer "B.Cu")
			(hatch none 0.5)
			(connect_pads
				(clearance 0)
			)
			(min_thickness 0.25)
			(keepout
				(tracks not_allowed)
				(vias allowed)
				(pads allowed)
				(copperpour not_allowed)
				(footprints allowed)
			)
			(placement
				(enabled no)
				(sheetname "")
			)
			(fill
				(thermal_gap 0.5)
				(thermal_bridge_width 0.5)
				(island_removal_mode 0)
			)
			(polygon
				(pts
					(xy 274.627086 -68.68414) (xy 275.897086 -68.68414) (xy 275.897086 -69.44614) (xy 274.627086 -69.44614)
				)
			)
		)
	)
)
